# BASEBOARD_FAB2 (Tioga Pass) — schematic netlist excerpt (pin names and nets, part order shuffled) for the footprints in the layout excerpt that follows; sources: Cadence DE-HDL packaged netlist, KiCad conversion of Wiwynn_Tioga_Pass_MB.brd

J1A1  SCONN288_H44441004  SCONN  pkg PIP  page 87
  \12v\(1)  = P12V_NVDIMM_KLM
  VSS(93)  = GND
  DQ(4)  = M_M_DQ<5>
  VSS(92)  = GND
  DQ(0)  = M_M_DQ<1>
  VSS(91)  = GND
  DQS9P  = M_M_DQS_DP<9>
  DQS9N  = M_M_DQS_DN<9>
  VSS(90)  = GND
  DQ(6)  = M_M_DQ<7>
  VSS(89)  = GND
  DQ(2)  = M_M_DQ<3>
  VSS(88)  = GND
  DQ(12)  = M_M_DQ<13>
  VSS(87)  = GND
  DQ(8)  = M_M_DQ<9>
  VSS(86)  = GND
  DQS10P  = M_M_DQS_DP<10>
  DQS10N  = M_M_DQS_DN<10>
  VSS(85)  = GND
  DQ(14)  = M_M_DQ<15>
  VSS(84)  = GND
  DQ(10)  = M_M_DQ<11>
  VSS(83)  = GND
  DQ(20)  = M_M_DQ<21>
  VSS(82)  = GND
  DQ(16)  = M_M_DQ<17>
  VSS(81)  = GND
  DQS11P  = M_M_DQS_DP<11>
  DQS11N  = M_M_DQS_DN<11>
  VSS(80)  = GND
  DQ(22)  = M_M_DQ<23>
  VSS(79)  = GND
  DQ(18)  = M_M_DQ<19>
  VSS(78)  = GND
  DQ(28)  = M_M_DQ<29>
  VSS(77)  = GND
  DQ(24)  = M_M_DQ<25>
  VSS(76)  = GND
  DQS12P  = M_M_DQS_DP<12>
  DQS12N  = M_M_DQS_DN<12>
  VSS(75)  = GND
  DQ(30)  = M_M_DQ<31>
  VSS(74)  = GND
  DQ(26)  = M_M_DQ<27>
  VSS(73)  = GND
  CB(4)  = M_M_ECC<5>
  VSS(72)  = GND
  CB(0)  = M_M_ECC<1>
  VSS(71)  = GND
  DQS17P  = M_M_DQS_DP<17>
  DQS17N  = M_M_DQS_DN<17>
  VSS(70)  = GND
  CB(6)  = M_M_ECC<7>
  VSS(69)  = GND
  CB(2)  = M_M_ECC<3>
  VSS(68)  = GND
  RESET_N  = M_KLM_RST_N
  VDD(25)  = PVDDQ_KLM
  CKE(0)  = M_M_CKE<0>
  VDD(24)  = PVDDQ_KLM
  ACT_N  = M_M_ACT_N
  BG(0)  = M_M_BG<0>
  VDD(23)  = PVDDQ_KLM
  A12  = M_M_MA<12>
  A9  = M_M_MA<9>
  VDD(22)  = PVDDQ_KLM
  A8  = M_M_MA<8>
  A6  = M_M_MA<6>
  VDD(21)  = PVDDQ_KLM
  A3  = M_M_MA<3>
  A1  = M_M_MA<1>
  VDD(20)  = PVDDQ_KLM
  CK0P  = M_M_CLK_DP<0>
  CK0N  = M_M_CLK_DN<0>
  VDD(19)  = PVDDQ_KLM
  VTT(1)  = PVTT_KLM
  EVENT_N  = FM_DIMM_EVENT_COD_N
  A0  = M_M_MA<0>
  VDD(18)  = PVDDQ_KLM
  BA(0)  = M_M_BA<0>
  A16_RAS_N  = M_M_MA<16>
  VDD(17)  = PVDDQ_KLM
  S0_N  = M_M_CS_N<0>
  VDD(16)  = PVDDQ_KLM
  A15_CAS_N  = M_M_MA<15>
  ODT(0)  = M_M_ODT<0>
  VDD(15)  = PVDDQ_KLM
  S1_N  = M_M_CS_N<1>
  VDD(14)  = PVDDQ_KLM
  ODT(1)  = M_M_ODT<1>
  VDD(13)  = PVDDQ_KLM
  S2_N_C(0)  = M_M_CS_N<2>
  VSS(67)  = GND
  DQ(36)  = M_M_DQ<37>
  VSS(66)  = GND
  DQ(32)  = M_M_DQ<33>
  VSS(65)  = GND
  DQS13P  = M_M_DQS_DP<13>
  DQS13N  = M_M_DQS_DN<13>
  VSS(64)  = GND
  DQ(38)  = M_M_DQ<39>
  VSS(63)  = GND
  DQ(34)  = M_M_DQ<35>
  VSS(62)  = GND
  DQ(44)  = M_M_DQ<45>
  VSS(61)  = GND
  DQ(40)  = M_M_DQ<41>
  VSS(60)  = GND
  DQS14P  = M_M_DQS_DP<14>
  DQS14N  = M_M_DQS_DN<14>
  VSS(59)  = GND
  DQ(46)  = M_M_DQ<47>
  VSS(58)  = GND
  DQ(42)  = M_M_DQ<43>
  VSS(57)  = GND
  DQ(52)  = M_M_DQ<53>
  VSS(56)  = GND
  DQ(48)  = M_M_DQ<49>
  VSS(55)  = GND
  DQS15P  = M_M_DQS_DP<15>
  DQS15N  = M_M_DQS_DN<15>
  VSS(54)  = GND
  DQ(54)  = M_M_DQ<55>
  VSS(53)  = GND
  DQ(50)  = M_M_DQ<51>
  VSS(52)  = GND
  DQ(60)  = M_M_DQ<61>
  VSS(51)  = GND
  DQ(56)  = M_M_DQ<57>
  VSS(50)  = GND
  DQS16P  = M_M_DQS_DP<16>
  DQS16N  = M_M_DQS_DN<16>
  VSS(49)  = GND
  DQ(62)  = M_M_DQ<63>
  VSS(48)  = GND
  DQ(58)  = M_M_DQ<59>
  VSS(47)  = GND
  SA(0)  = GND
  SA(1)  = GND
  SCL  = SMB_DDR_KLM_VPP_SCL
  VPP(4)  = PVPP_KLM
  VPP(3)  = PVPP_KLM
  RFU(2)  = TP_CH_M_DIMM_M0_RFU_2
  \12v\(0)  = P12V_NVDIMM_KLM
  VREFCA  = M_M_VREF
  VSS(46)  = GND
  DQ(5)  = M_M_DQ<4>
  VSS(45)  = GND
  DQ(1)  = M_M_DQ<0>
  VSS(44)  = GND
  DQS0N  = M_M_DQS_DN<0>
  DQS0P  = M_M_DQS_DP<0>
  VSS(43)  = GND
  DQ(7)  = M_M_DQ<6>
  VSS(42)  = GND
  DQ(3)  = M_M_DQ<2>
  VSS(41)  = GND
  DQ(13)  = M_M_DQ<12>
  VSS(40)  = GND
  DQ(9)  = M_M_DQ<8>
  VSS(39)  = GND
  DQS1N  = M_M_DQS_DN<1>
  DQS1P  = M_M_DQS_DP<1>
  VSS(38)  = GND
  DQ(15)  = M_M_DQ<14>
  VSS(37)  = GND
  DQ(11)  = M_M_DQ<10>
  VSS(36)  = GND
  DQ(21)  = M_M_DQ<20>
  VSS(35)  = GND
  DQ(17)  = M_M_DQ<16>
  VSS(34)  = GND
  DQS2N  = M_M_DQS_DN<2>
  DQS2P  = M_M_DQS_DP<2>
  VSS(33)  = GND
  DQ(23)  = M_M_DQ<22>
  VSS(32)  = GND
  DQ(19)  = M_M_DQ<18>
  VSS(31)  = GND
  DQ(29)  = M_M_DQ<28>
  VSS(30)  = GND
  DQ(25)  = M_M_DQ<24>
  VSS(29)  = GND
  DQS3N  = M_M_DQS_DN<3>
  DQS3P  = M_M_DQS_DP<3>
  VSS(28)  = GND
  DQ(31)  = M_M_DQ<30>
  VSS(27)  = GND
  DQ(27)  = M_M_DQ<26>
  VSS(26)  = GND
  CB(5)  = M_M_ECC<4>
  VSS(25)  = GND
  CB(1)  = M_M_ECC<0>
  VSS(24)  = GND
  DQS8N  = M_M_DQS_DN<8>
  DQS8P  = M_M_DQS_DP<8>
  VSS(23)  = GND
  CB(7)  = M_M_ECC<6>
  VSS(22)  = GND
  CB(3)  = M_M_ECC<2>
  VSS(21)  = GND
  CKE(1)  = M_M_CKE<1>
  VDD(12)  = PVDDQ_KLM
  RFU(0)  = TP_CH_M_DIMM_M0_RFU_0
  VDD(11)  = PVDDQ_KLM
  BG(1)  = M_M_BG<1>
  ALERT_N  = M_M_ALERT_N
  VDD(10)  = PVDDQ_KLM
  A11  = M_M_MA<11>
  A7  = M_M_MA<7>
  VDD(9)  = PVDDQ_KLM
  A5  = M_M_MA<5>
  A4  = M_M_MA<4>
  VDD(8)  = PVDDQ_KLM
  A2  = M_M_MA<2>
  VDD(7)  = PVDDQ_KLM
  CK1P  = M_M_CLK_DP<1>
  CK1N  = M_M_CLK_DN<1>
  VDD(6)  = PVDDQ_KLM
  VTT(0)  = PVTT_KLM
  PAR  = M_M_PAR
  VDD(5)  = PVDDQ_KLM
  BA(1)  = M_M_BA<1>
  A10  = M_M_MA<10>
  VDD(4)  = PVDDQ_KLM
  RFU(1)  = TP_CH_M_DIMM_M0_RFU_1
  A14_WE_N  = M_M_MA<14>
  VDD(3)  = PVDDQ_KLM
  SAVE_N_NC  = FM_ADR_COMPLETE_KLM_N
  VDD(2)  = PVDDQ_KLM
  A13  = M_M_MA<13>
  VDD(1)  = PVDDQ_KLM
  A17  = M_M_MA<17>
  C(2)  = M_M_C<2>
  VDD(0)  = PVDDQ_KLM
  S3_N_C(1)  = M_M_CS_N<3>
  SA(2)  = PVPP_KLM
  VSS(20)  = GND
  DQ(37)  = M_M_DQ<36>
  VSS(19)  = GND
  DQ(33)  = M_M_DQ<32>
  VSS(18)  = GND
  DQS4N  = M_M_DQS_DN<4>
  DQS4P  = M_M_DQS_DP<4>
  VSS(17)  = GND
  DQ(39)  = M_M_DQ<38>
  VSS(16)  = GND
  DQ(35)  = M_M_DQ<34>
  VSS(15)  = GND
  DQ(45)  = M_M_DQ<44>
  VSS(14)  = GND
  DQ(41)  = M_M_DQ<40>
  VSS(13)  = GND
  DQS5N  = M_M_DQS_DN<5>
  DQS5P  = M_M_DQS_DP<5>
  VSS(12)  = GND
  DQ(47)  = M_M_DQ<46>
  VSS(11)  = GND
  DQ(43)  = M_M_DQ<42>
  VSS(10)  = GND
  DQ(53)  = M_M_DQ<52>
  VSS(9)  = GND
  DQ(49)  = M_M_DQ<48>
  VSS(8)  = GND
  DQS6N  = M_M_DQS_DN<6>
  DQS6P  = M_M_DQS_DP<6>
  VSS(7)  = GND
  DQ(55)  = M_M_DQ<54>
  VSS(6)  = GND
  DQ(51)  = M_M_DQ<50>
  VSS(5)  = GND
  DQ(61)  = M_M_DQ<60>
  VSS(4)  = GND
  DQ(57)  = M_M_DQ<56>
  VSS(3)  = GND
  DQS7N  = M_M_DQS_DN<7>
  DQS7P  = M_M_DQS_DP<7>
  VSS(2)  = GND
  DQ(63)  = M_M_DQ<62>
  VSS(1)  = GND
  DQ(59)  = M_M_DQ<58>
  VSS(0)  = GND
  VDDSPD  = PVPP_KLM
  SDA  = SMB_DDR_KLM_VPP_SDA
  VPP(1)  = PVPP_KLM
  VPP(0)  = PVPP_KLM
  VPP(2)  = PVPP_KLM

(kicad_pcb
	(version 20260206)
	(generator "pcbnew")
	(generator_version "10.0")
	(general
		(thickness 1.6)
		(legacy_teardrops no)
	)
	(paper "A4")
	(title_block
		(title "Wiwynn_Tioga_Pass_MB.brd")
		(comment 1 "Tioga Pass / footprint 830 of 4770 (J1A1), pads 102-152 of 291")
	)
	(layers
		(0 "F.Cu" signal "TOP")
		(4 "In1.Cu" signal "L2GND")
		(6 "In2.Cu" signal "L3")
		(8 "In3.Cu" signal "L4GND")
		(10 "In4.Cu" signal "L5")
		(12 "In5.Cu" signal "L6GND")
		(14 "In6.Cu" signal "L7VCC")
		(16 "In7.Cu" signal "L8VCC")
		(18 "In8.Cu" signal "L9GND")
		(20 "In9.Cu" signal "L10")
		(22 "In10.Cu" signal "L11GND")
		(24 "In11.Cu" signal "L12")
		(26 "In12.Cu" signal "L13GND")
		(2 "B.Cu" signal "BOTTOM")
		(9 "F.Adhes" user "F.Adhesive")
		(11 "B.Adhes" user "B.Adhesive")
		(13 "F.Paste" user "Package Geometry/Pastemask Top")
		(15 "B.Paste" user "Package Geometry/Pastemask Bottom")
		(5 "F.SilkS" user "Ref Des/Silkscreen Top")
		(7 "B.SilkS" user "Ref Des/Silkscreen Bottom")
		(1 "F.Mask" user "Board Geometry/Soldermask Top")
		(3 "B.Mask" user "Board Geometry/Soldermask Bottom")
		(17 "Dwgs.User" user "User.Drawings")
		(19 "Cmts.User" user "User.Comments")
		(21 "Eco1.User" user "User.Eco1")
		(23 "Eco2.User" user "User.Eco2")
		(25 "Edge.Cuts" user "Board Geometry/Outline")
		(27 "Margin" user)
		(31 "F.CrtYd" user "Package Geometry/Place Bound Top")
		(29 "B.CrtYd" user "Package Geometry/Place Bound Bottom")
		(35 "F.Fab" user "Ref Des/Assembly Top")
		(33 "B.Fab" user "Ref Des/Assembly Bottom")
	)
	(footprint ""
		(layer "F.Cu")
		(at 29.699458 -152.273 90)
		(property "Reference" "J1A1"
			(at -2.572512 42.563542 0)
			(unlocked yes)
			(layer "F.SilkS")
			(effects
				(font
					(size 0.7874 0.5842)
					(thickness 0.1524)
				)
				(justify left)
			)
		)
		(property "Value" ""
			(at 0 0 90)
			(layer "F.Fab")
			(effects
				(font
					(size 1.27 1.27)
				)
			)
		)
		(duplicate_pad_numbers_are_jumpers no)
		(pad "99" smd rect
			(at 0 88.399874 90)
			(size 1.8034 0.508)
			(layers "F.Cu" "F.Mask" "F.Paste")
			(net "M_M_DQS_DP<13>")
		)
		(pad "100" smd rect
			(at 0 89.250012 90)
			(size 1.8034 0.508)
			(layers "F.Cu" "F.Mask" "F.Paste")
			(net "M_M_DQS_DN<13>")
		)
		(pad "101" smd rect
			(at 0 90.099896 90)
			(size 1.8034 0.508)
			(layers "F.Cu" "F.Mask" "F.Paste")
			(net "GND")
		)
		(pad "102" smd rect
			(at 0 90.950034 90)
			(size 1.8034 0.508)
			(layers "F.Cu" "F.Mask" "F.Paste")
			(net "M_M_DQ<39>")
		)
		(pad "103" smd rect
			(at 0 91.799918 90)
			(size 1.8034 0.508)
			(layers "F.Cu" "F.Mask" "F.Paste")
			(net "GND")
		)
		(pad "104" smd rect
			(at 0 92.650056 90)
			(size 1.8034 0.508)
			(layers "F.Cu" "F.Mask" "F.Paste")
			(net "M_M_DQ<35>")
		)
		(pad "105" smd rect
			(at 0 93.49994 90)
			(size 1.8034 0.508)
			(layers "F.Cu" "F.Mask" "F.Paste")
			(net "GND")
		)
		(pad "106" smd rect
			(at 0 94.350078 90)
			(size 1.8034 0.508)
			(layers "F.Cu" "F.Mask" "F.Paste")
			(net "M_M_DQ<45>")
		)
		(pad "107" smd rect
			(at 0 95.199962 90)
			(size 1.8034 0.508)
			(layers "F.Cu" "F.Mask" "F.Paste")
			(net "GND")
		)
		(pad "108" smd rect
			(at 0 96.0501 90)
			(size 1.8034 0.508)
			(layers "F.Cu" "F.Mask" "F.Paste")
			(net "M_M_DQ<41>")
		)
		(pad "109" smd rect
			(at 0 96.899984 90)
			(size 1.8034 0.508)
			(layers "F.Cu" "F.Mask" "F.Paste")
			(net "GND")
		)
		(pad "110" smd rect
			(at 0 97.750122 90)
			(size 1.8034 0.508)
			(layers "F.Cu" "F.Mask" "F.Paste")
			(net "M_M_DQS_DP<14>")
		)
		(pad "111" smd rect
			(at 0 98.600006 90)
			(size 1.8034 0.508)
			(layers "F.Cu" "F.Mask" "F.Paste")
			(net "M_M_DQS_DN<14>")
		)
		(pad "112" smd rect
			(at 0 99.44989 90)
			(size 1.8034 0.508)
			(layers "F.Cu" "F.Mask" "F.Paste")
			(net "GND")
		)
		(pad "113" smd rect
			(at 0 100.300028 90)
			(size 1.8034 0.508)
			(layers "F.Cu" "F.Mask" "F.Paste")
			(net "M_M_DQ<47>")
		)
		(pad "114" smd rect
			(at 0 101.149912 90)
			(size 1.8034 0.508)
			(layers "F.Cu" "F.Mask" "F.Paste")
			(net "GND")
		)
		(pad "115" smd rect
			(at 0 102.00005 90)
			(size 1.8034 0.508)
			(layers "F.Cu" "F.Mask" "F.Paste")
			(net "M_M_DQ<43>")
		)
		(pad "116" smd rect
			(at 0 102.849934 90)
			(size 1.8034 0.508)
			(layers "F.Cu" "F.Mask" "F.Paste")
			(net "GND")
		)
		(pad "117" smd rect
			(at 0 103.700072 90)
			(size 1.8034 0.508)
			(layers "F.Cu" "F.Mask" "F.Paste")
			(net "M_M_DQ<53>")
		)
		(pad "118" smd rect
			(at 0 104.549956 90)
			(size 1.8034 0.508)
			(layers "F.Cu" "F.Mask" "F.Paste")
			(net "GND")
		)
		(pad "119" smd rect
			(at 0 105.400094 90)
			(size 1.8034 0.508)
			(layers "F.Cu" "F.Mask" "F.Paste")
			(net "M_M_DQ<49>")
		)
		(pad "120" smd rect
			(at 0 106.249978 90)
			(size 1.8034 0.508)
			(layers "F.Cu" "F.Mask" "F.Paste")
			(net "GND")
		)
		(pad "121" smd rect
			(at 0 107.100116 90)
			(size 1.8034 0.508)
			(layers "F.Cu" "F.Mask" "F.Paste")
			(net "M_M_DQS_DP<15>")
		)
		(pad "122" smd rect
			(at 0 107.95 90)
			(size 1.8034 0.508)
			(layers "F.Cu" "F.Mask" "F.Paste")
			(net "M_M_DQS_DN<15>")
		)
		(pad "123" smd rect
			(at 0 108.799884 90)
			(size 1.8034 0.508)
			(layers "F.Cu" "F.Mask" "F.Paste")
			(net "GND")
		)
		(pad "124" smd rect
			(at 0 109.650022 90)
			(size 1.8034 0.508)
			(layers "F.Cu" "F.Mask" "F.Paste")
			(net "M_M_DQ<55>")
		)
		(pad "125" smd rect
			(at 0 110.499906 90)
			(size 1.8034 0.508)
			(layers "F.Cu" "F.Mask" "F.Paste")
			(net "GND")
		)
		(pad "126" smd rect
			(at 0 111.350044 90)
			(size 1.8034 0.508)
			(layers "F.Cu" "F.Mask" "F.Paste")
			(net "M_M_DQ<51>")
		)
		(pad "127" smd rect
			(at 0 112.199928 90)
			(size 1.8034 0.508)
			(layers "F.Cu" "F.Mask" "F.Paste")
			(net "GND")
		)
		(pad "128" smd rect
			(at 0 113.050066 90)
			(size 1.8034 0.508)
			(layers "F.Cu" "F.Mask" "F.Paste")
			(net "M_M_DQ<61>")
		)
		(pad "129" smd rect
			(at 0 113.89995 90)
			(size 1.8034 0.508)
			(layers "F.Cu" "F.Mask" "F.Paste")
			(net "GND")
		)
		(pad "130" smd rect
			(at 0 114.750088 90)
			(size 1.8034 0.508)
			(layers "F.Cu" "F.Mask" "F.Paste")
			(net "M_M_DQ<57>")
		)
		(pad "131" smd rect
			(at 0 115.599972 90)
			(size 1.8034 0.508)
			(layers "F.Cu" "F.Mask" "F.Paste")
			(net "GND")
		)
		(pad "132" smd rect
			(at 0 116.45011 90)
			(size 1.8034 0.508)
			(layers "F.Cu" "F.Mask" "F.Paste")
			(net "M_M_DQS_DP<16>")
		)
		(pad "133" smd rect
			(at 0 117.299994 90)
			(size 1.8034 0.508)
			(layers "F.Cu" "F.Mask" "F.Paste")
			(net "M_M_DQS_DN<16>")
		)
		(pad "134" smd rect
			(at 0 118.149878 90)
			(size 1.8034 0.508)
			(layers "F.Cu" "F.Mask" "F.Paste")
			(net "GND")
		)
		(pad "135" smd rect
			(at 0 119.000016 90)
			(size 1.8034 0.508)
			(layers "F.Cu" "F.Mask" "F.Paste")
			(net "M_M_DQ<63>")
		)
		(pad "136" smd rect
			(at 0 119.8499 90)
			(size 1.8034 0.508)
			(layers "F.Cu" "F.Mask" "F.Paste")
			(net "GND")
		)
		(pad "137" smd rect
			(at 0 120.700038 90)
			(size 1.8034 0.508)
			(layers "F.Cu" "F.Mask" "F.Paste")
			(net "M_M_DQ<59>")
		)
		(pad "138" smd rect
			(at 0 121.549922 90)
			(size 1.8034 0.508)
			(layers "F.Cu" "F.Mask" "F.Paste")
			(net "GND")
		)
		(pad "139" smd rect
			(at 0 122.40006 90)
			(size 1.8034 0.508)
			(layers "F.Cu" "F.Mask" "F.Paste")
			(net "GND")
		)
		(pad "140" smd rect
			(at 0 123.249944 90)
			(size 1.8034 0.508)
			(layers "F.Cu" "F.Mask" "F.Paste")
			(net "GND")
		)
		(pad "141" smd rect
			(at 0 124.100082 90)
			(size 1.8034 0.508)
			(layers "F.Cu" "F.Mask" "F.Paste")
			(net "SMB_DDR_KLM_VPP_SCL")
		)
		(pad "142" smd rect
			(at 0 124.949966 90)
			(size 1.8034 0.508)
			(layers "F.Cu" "F.Mask" "F.Paste")
			(net "PVPP_KLM")
		)
		(pad "143" smd rect
			(at 0 125.800104 90)
			(size 1.8034 0.508)
			(layers "F.Cu" "F.Mask" "F.Paste")
			(net "PVPP_KLM")
		)
		(pad "144" smd rect
			(at 0 126.649988 90)
			(size 1.8034 0.508)
			(layers "F.Cu" "F.Mask" "F.Paste")
			(net "TP_CH_M_DIMM_M0_RFU_2")
		)
		(pad "145" smd rect
			(at 4.59994 0 90)
			(size 1.8034 0.508)
			(layers "F.Cu" "F.Mask" "F.Paste")
			(net "P12V_NVDIMM_KLM")
		)
		(pad "146" smd rect
			(at 4.59994 0.849884 90)
			(size 1.8034 0.508)
			(layers "F.Cu" "F.Mask" "F.Paste")
			(net "M_M_VREF")
		)
		(pad "147" smd rect
			(at 4.59994 1.700022 90)
			(size 1.8034 0.508)
			(layers "F.Cu" "F.Mask" "F.Paste")
			(net "GND")
		)
		(pad "148" smd rect
			(at 4.59994 2.549906 90)
			(size 1.8034 0.508)
			(layers "F.Cu" "F.Mask" "F.Paste")
			(net "M_M_DQ<4>")
		)
		(pad "149" smd rect
			(at 4.59994 3.400044 90)
			(size 1.8034 0.508)
			(layers "F.Cu" "F.Mask" "F.Paste")
			(net "GND")
		)
	)
)
